# T6G (Grand Teton) — schematic netlist excerpt (pin names and nets, part order shuffled) for the footprints in the layout excerpt that follows; sources: Cadence DE-HDL packaged netlist, KiCad conversion of 04192023_DAF0TMB3IC0_F0TG_MB_C_brd_V02_OCP.brd

R5026  Q_RES  4.7K 5% EMPTY  pkg 0402LF  page 28 : A = GND ; B = FM_SMM_CRASHDUMP
PR530  Q_RES  0 5% CHIP  pkg 0402LF  page 210 : A = NC_PVDDCR_CPU0_P1_IMON7 ; B = GND

(kicad_pcb
	(version 20260206)
	(generator "pcbnew")
	(generator_version "10.0")
	(general
		(thickness 1.6)
		(legacy_teardrops no)
	)
	(paper "A4")
	(title_block
		(title "04192023_DAF0TMB3IC0_F0TG_MB_C_brd_V02_OCP.brd")
		(comment 1 "Grand Teton / footprints 4987-4988 of 8354")
	)
	(layers
		(0 "F.Cu" signal "TOP")
		(4 "In1.Cu" signal "GND")
		(6 "In2.Cu" signal "IN1")
		(8 "In3.Cu" signal "GND1")
		(10 "In4.Cu" signal "IN2")
		(12 "In5.Cu" signal "GND2")
		(14 "In6.Cu" signal "IN3")
		(16 "In7.Cu" signal "GND3")
		(18 "In8.Cu" signal "VCC")
		(20 "In9.Cu" signal "VCC1")
		(22 "In10.Cu" signal "GND4")
		(24 "In11.Cu" signal "IN4")
		(26 "In12.Cu" signal "GND5")
		(28 "In13.Cu" signal "IN5")
		(30 "In14.Cu" signal "GND6")
		(32 "In15.Cu" signal "IN6")
		(34 "In16.Cu" signal "GND7")
		(2 "B.Cu" signal "BOTTOM")
		(9 "F.Adhes" user "F.Adhesive")
		(11 "B.Adhes" user "B.Adhesive")
		(13 "F.Paste" user "Package Geometry/Pastemask Top")
		(15 "B.Paste" user "Package Geometry/Pastemask Bottom")
		(5 "F.SilkS" user "Ref Des/Silkscreen Top")
		(7 "B.SilkS" user "Ref Des/Silkscreen Bottom")
		(1 "F.Mask" user "Board Geometry/Soldermask Top")
		(3 "B.Mask" user "Board Geometry/Soldermask Bottom")
		(17 "Dwgs.User" user "User.Drawings")
		(19 "Cmts.User" user "User.Comments")
		(21 "Eco1.User" user "User.Eco1")
		(23 "Eco2.User" user "User.Eco2")
		(25 "Edge.Cuts" user "Board Geometry/Outline")
		(27 "Margin" user)
		(31 "F.CrtYd" user "Package Geometry/Place Bound Top")
		(29 "B.CrtYd" user "Package Geometry/Place Bound Bottom")
		(35 "F.Fab" user "Ref Des/Assembly Top")
		(33 "B.Fab" user "Ref Des/Assembly Bottom")
	)
	(footprint ""
		(layer "B.Cu")
		(at 408.316684 -332.118462 180)
		(property "Reference" "R5026"
			(at 0 0 0)
			(layer "B.SilkS")
			(hide yes)
			(effects
				(font
					(size 1.27 1.27)
				)
				(justify mirror)
			)
		)
		(property "Value" ""
			(at 0 0 0)
			(layer "B.Fab")
			(effects
				(font
					(size 1.27 1.27)
				)
				(justify mirror)
			)
		)
		(duplicate_pad_numbers_are_jumpers no)
		(fp_line
			(start 0.7874 0.4064)
			(end 0.7874 -0.4064)
			(stroke
				(width 0.1524)
				(type default)
			)
			(layer "B.SilkS")
		)
		(fp_line
			(start 0.7874 -0.4064)
			(end -0.7874 -0.4064)
			(stroke
				(width 0.1524)
				(type default)
			)
			(layer "B.SilkS")
		)
		(fp_line
			(start -0.7874 0.4064)
			(end 0.7874 0.4064)
			(stroke
				(width 0.1524)
				(type default)
			)
			(layer "B.SilkS")
		)
		(fp_line
			(start -0.7874 -0.4064)
			(end -0.7874 0.4064)
			(stroke
				(width 0.1524)
				(type default)
			)
			(layer "B.SilkS")
		)
		(fp_line
			(start 0.67945 0.3048)
			(end 0.67945 -0.305054)
			(stroke
				(width 0.1)
				(type default)
			)
			(layer "B.Fab")
		)
		(fp_line
			(start 0.67945 -0.305054)
			(end 0.12065 -0.305054)
			(stroke
				(width 0.1)
				(type default)
			)
			(layer "B.Fab")
		)
		(fp_line
			(start 0.12065 0.3048)
			(end 0.67945 0.3048)
			(stroke
				(width 0.1)
				(type default)
			)
			(layer "B.Fab")
		)
		(fp_line
			(start 0.12065 0.2794)
			(end 0.12065 0.3048)
			(stroke
				(width 0.1)
				(type default)
			)
			(layer "B.Fab")
		)
		(fp_line
			(start 0.12065 -0.2794)
			(end -0.12065 -0.2794)
			(stroke
				(width 0.1)
				(type default)
			)
			(layer "B.Fab")
		)
		(fp_line
			(start 0.12065 -0.305054)
			(end 0.12065 -0.2794)
			(stroke
				(width 0.1)
				(type default)
			)
			(layer "B.Fab")
		)
		(fp_line
			(start -0.120396 0.3048)
			(end -0.120396 0.2794)
			(stroke
				(width 0.1)
				(type default)
			)
			(layer "B.Fab")
		)
		(fp_line
			(start -0.120396 0.2794)
			(end 0.12065 0.2794)
			(stroke
				(width 0.1)
				(type default)
			)
			(layer "B.Fab")
		)
		(fp_line
			(start -0.12065 -0.2794)
			(end -0.12065 -0.3048)
			(stroke
				(width 0.1)
				(type default)
			)
			(layer "B.Fab")
		)
		(fp_line
			(start -0.12065 -0.3048)
			(end -0.67945 -0.3048)
			(stroke
				(width 0.1)
				(type default)
			)
			(layer "B.Fab")
		)
		(fp_line
			(start -0.67945 0.3048)
			(end -0.120396 0.3048)
			(stroke
				(width 0.1)
				(type default)
			)
			(layer "B.Fab")
		)
		(fp_line
			(start -0.67945 -0.3048)
			(end -0.67945 0.3048)
			(stroke
				(width 0.1)
				(type default)
			)
			(layer "B.Fab")
		)
		(pad "1" smd circle
			(at 0.40005 0)
			(size 0 0)
			(layers "B.Cu" "B.Mask" "B.Paste")
			(net "GND")
		)
		(pad "2" smd circle
			(at -0.40005 0)
			(size 0 0)
			(layers "B.Cu" "B.Mask" "B.Paste")
			(net "FM_SMM_CRASHDUMP")
		)
	)
	(footprint ""
		(layer "B.Cu")
		(at 96.886522 -150.698962 -90)
		(property "Reference" "PR530"
			(at 0 0 90)
			(layer "B.SilkS")
			(hide yes)
			(effects
				(font
					(size 1.27 1.27)
				)
				(justify mirror)
			)
		)
		(property "Value" ""
			(at 0 0 90)
			(layer "B.Fab")
			(effects
				(font
					(size 1.27 1.27)
				)
				(justify mirror)
			)
		)
		(duplicate_pad_numbers_are_jumpers no)
		(fp_line
			(start -0.7874 0.4064)
			(end 0.7874 0.4064)
			(stroke
				(width 0.1524)
				(type default)
			)
			(layer "B.SilkS")
		)
		(fp_line
			(start 0.7874 0.4064)
			(end 0.7874 -0.4064)
			(stroke
				(width 0.1524)
				(type default)
			)
			(layer "B.SilkS")
		)
		(fp_line
			(start -0.7874 -0.4064)
			(end -0.7874 0.4064)
			(stroke
				(width 0.1524)
				(type default)
			)
			(layer "B.SilkS")
		)
		(fp_line
			(start 0.7874 -0.4064)
			(end -0.7874 -0.4064)
			(stroke
				(width 0.1524)
				(type default)
			)
			(layer "B.SilkS")
		)
		(fp_line
			(start -0.67945 0.3048)
			(end -0.120396 0.3048)
			(stroke
				(width 0.1)
				(type default)
			)
			(layer "B.Fab")
		)
		(fp_line
			(start -0.120396 0.3048)
			(end -0.120396 0.2794)
			(stroke
				(width 0.1)
				(type default)
			)
			(layer "B.Fab")
		)
		(fp_line
			(start 0.12065 0.3048)
			(end 0.67945 0.3048)
			(stroke
				(width 0.1)
				(type default)
			)
			(layer "B.Fab")
		)
		(fp_line
			(start 0.67945 0.3048)
			(end 0.67945 -0.305054)
			(stroke
				(width 0.1)
				(type default)
			)
			(layer "B.Fab")
		)
		(fp_line
			(start -0.120396 0.2794)
			(end 0.12065 0.2794)
			(stroke
				(width 0.1)
				(type default)
			)
			(layer "B.Fab")
		)
		(fp_line
			(start 0.12065 0.2794)
			(end 0.12065 0.3048)
			(stroke
				(width 0.1)
				(type default)
			)
			(layer "B.Fab")
		)
		(fp_line
			(start -0.12065 -0.2794)
			(end -0.12065 -0.3048)
			(stroke
				(width 0.1)
				(type default)
			)
			(layer "B.Fab")
		)
		(fp_line
			(start 0.12065 -0.2794)
			(end -0.12065 -0.2794)
			(stroke
				(width 0.1)
				(type default)
			)
			(layer "B.Fab")
		)
		(fp_line
			(start -0.67945 -0.3048)
			(end -0.67945 0.3048)
			(stroke
				(width 0.1)
				(type default)
			)
			(layer "B.Fab")
		)
		(fp_line
			(start -0.12065 -0.3048)
			(end -0.67945 -0.3048)
			(stroke
				(width 0.1)
				(type default)
			)
			(layer "B.Fab")
		)
		(fp_line
			(start 0.12065 -0.305054)
			(end 0.12065 -0.2794)
			(stroke
				(width 0.1)
				(type default)
			)
			(layer "B.Fab")
		)
		(fp_line
			(start 0.67945 -0.305054)
			(end 0.12065 -0.305054)
			(stroke
				(width 0.1)
				(type default)
			)
			(layer "B.Fab")
		)
		(pad "1" smd circle
			(at 0.40005 0 90)
			(size 0 0)
			(layers "B.Cu" "B.Mask" "B.Paste")
			(net "NC_PVDDCR_CPU0_P1_IMON7")
		)
		(pad "2" smd circle
			(at -0.40005 0 90)
			(size 0 0)
			(layers "B.Cu" "B.Mask" "B.Paste")
			(net "GND")
		)
	)
)
